# BASEBOARD_FAB2 (Tioga Pass) — schematic netlist excerpt (pin names and nets, part order shuffled) for the footprints in the layout excerpt that follows; sources: Cadence DE-HDL packaged netlist, KiCad conversion of Wiwynn_Tioga_Pass_MB.brd

R8W7  RES  1.37K 1% CHIP  pkg 0402  page 138 : A = P3V3_STBY ; B = SMB_VR_STBY_LVC3_SCL_R1
C2R13  CAP  0.22UF 16V 10% X7R  pkg 0402  page 106 : A = P3E_CPU0_PE3_OCP_TXN<5> ; B = P3E_OCP_CPU0_PE3_C_TXN<5>

(kicad_pcb
	(version 20260206)
	(generator "pcbnew")
	(generator_version "10.0")
	(general
		(thickness 1.6)
		(legacy_teardrops no)
	)
	(paper "A4")
	(title_block
		(title "Wiwynn_Tioga_Pass_MB.brd")
		(comment 1 "Tioga Pass / footprints 4541-4542 of 4770")
	)
	(layers
		(0 "F.Cu" signal "TOP")
		(4 "In1.Cu" signal "L2GND")
		(6 "In2.Cu" signal "L3")
		(8 "In3.Cu" signal "L4GND")
		(10 "In4.Cu" signal "L5")
		(12 "In5.Cu" signal "L6GND")
		(14 "In6.Cu" signal "L7VCC")
		(16 "In7.Cu" signal "L8VCC")
		(18 "In8.Cu" signal "L9GND")
		(20 "In9.Cu" signal "L10")
		(22 "In10.Cu" signal "L11GND")
		(24 "In11.Cu" signal "L12")
		(26 "In12.Cu" signal "L13GND")
		(2 "B.Cu" signal "BOTTOM")
		(9 "F.Adhes" user "F.Adhesive")
		(11 "B.Adhes" user "B.Adhesive")
		(13 "F.Paste" user "Package Geometry/Pastemask Top")
		(15 "B.Paste" user "Package Geometry/Pastemask Bottom")
		(5 "F.SilkS" user "Ref Des/Silkscreen Top")
		(7 "B.SilkS" user "Ref Des/Silkscreen Bottom")
		(1 "F.Mask" user "Board Geometry/Soldermask Top")
		(3 "B.Mask" user "Board Geometry/Soldermask Bottom")
		(17 "Dwgs.User" user "User.Drawings")
		(19 "Cmts.User" user "User.Comments")
		(21 "Eco1.User" user "User.Eco1")
		(23 "Eco2.User" user "User.Eco2")
		(25 "Edge.Cuts" user "Board Geometry/Outline")
		(27 "Margin" user)
		(31 "F.CrtYd" user "Package Geometry/Place Bound Top")
		(29 "B.CrtYd" user "Package Geometry/Place Bound Bottom")
		(35 "F.Fab" user "Ref Des/Assembly Top")
		(33 "B.Fab" user "Ref Des/Assembly Bottom")
	)
	(footprint ""
		(layer "B.Cu")
		(at 396.875 -87.3252 180)
		(property "Reference" "R8W7"
			(at 0.8382 -0.67818 180)
			(unlocked yes)
			(layer "B.SilkS")
			(effects
				(font
					(size 0.4064 0.254)
					(thickness 0.1524)
				)
				(justify left mirror)
			)
		)
		(property "Value" ""
			(at 0 0 0)
			(layer "B.Fab")
			(effects
				(font
					(size 1.27 1.27)
				)
				(justify mirror)
			)
		)
		(duplicate_pad_numbers_are_jumpers no)
		(fp_poly
			(pts
				(xy 0.2794 -0.1016) (xy -0.2794 -0.1016) (xy -0.2794 0.9906) (xy 0.2794 0.9906)
			)
			(stroke
				(width 0)
				(type default)
			)
			(fill no)
			(layer "B.CrtYd")
		)
		(fp_line
			(start 0.2794 0.9906)
			(end -0.2794 0.9906)
			(stroke
				(width 0.1)
				(type default)
			)
			(layer "B.Fab")
		)
		(fp_line
			(start 0.2794 -0.1016)
			(end 0.2794 0.9906)
			(stroke
				(width 0.1)
				(type default)
			)
			(layer "B.Fab")
		)
		(fp_line
			(start -0.2794 0.9906)
			(end -0.2794 -0.1016)
			(stroke
				(width 0.1)
				(type default)
			)
			(layer "B.Fab")
		)
		(fp_line
			(start -0.2794 -0.1016)
			(end 0.2794 -0.1016)
			(stroke
				(width 0.1)
				(type default)
			)
			(layer "B.Fab")
		)
		(pad "1" smd rect
			(at 0 0)
			(size 0.508 0.508)
			(layers "B.Cu" "B.Mask" "B.Paste")
			(net "P3V3_STBY")
		)
		(pad "2" smd rect
			(at 0 0.889)
			(size 0.508 0.508)
			(layers "B.Cu" "B.Mask" "B.Paste")
			(net "SMB_VR_STBY_LVC3_SCL_R1")
		)
		(zone
			(layer "B.Cu")
			(hatch none 0.5)
			(connect_pads
				(clearance 0)
			)
			(min_thickness 0.25)
			(keepout
				(tracks not_allowed)
				(vias allowed)
				(pads allowed)
				(copperpour not_allowed)
				(footprints allowed)
			)
			(placement
				(enabled no)
				(sheetname "")
			)
			(fill
				(thermal_gap 0.5)
				(thermal_bridge_width 0.5)
				(island_removal_mode 0)
			)
			(polygon
				(pts
					(xy 396.621 -87.9602) (xy 397.129 -87.9602) (xy 397.129 -87.5792) (xy 396.621 -87.5792)
				)
			)
		)
		(zone
			(layer "B.Cu")
			(hatch none 0.5)
			(connect_pads
				(clearance 0)
			)
			(min_thickness 0.25)
			(keepout
				(tracks allowed)
				(vias not_allowed)
				(pads allowed)
				(copperpour not_allowed)
				(footprints allowed)
			)
			(placement
				(enabled no)
				(sheetname "")
			)
			(fill
				(thermal_gap 0.5)
				(thermal_bridge_width 0.5)
				(island_removal_mode 0)
			)
			(polygon
				(pts
					(xy 396.621 -87.5792) (xy 397.129 -87.5792) (xy 397.129 -87.9602) (xy 396.621 -87.9602)
				)
			)
		)
	)
	(footprint ""
		(layer "B.Cu")
		(at 447.928238 -52.407058)
		(property "Reference" "C2R13"
			(at 0 0 0)
			(layer "B.SilkS")
			(hide yes)
			(effects
				(font
					(size 1.27 1.27)
				)
				(justify mirror)
			)
		)
		(property "Value" ""
			(at 0 0 0)
			(layer "B.Fab")
			(effects
				(font
					(size 1.27 1.27)
				)
				(justify mirror)
			)
		)
		(duplicate_pad_numbers_are_jumpers no)
		(fp_poly
			(pts
				(xy -0.3048 -0.1016) (xy -0.3048 0.9906) (xy 0.3048 0.9906) (xy 0.3048 -0.1016)
			)
			(stroke
				(width 0)
				(type default)
			)
			(fill no)
			(layer "B.CrtYd")
		)
		(fp_line
			(start -0.3048 -0.1016)
			(end 0.3048 -0.1016)
			(stroke
				(width 0.1)
				(type default)
			)
			(layer "B.Fab")
		)
		(fp_line
			(start -0.3048 0.9906)
			(end -0.3048 -0.1016)
			(stroke
				(width 0.1)
				(type default)
			)
			(layer "B.Fab")
		)
		(fp_line
			(start 0.3048 -0.1016)
			(end 0.3048 0.9906)
			(stroke
				(width 0.1)
				(type default)
			)
			(layer "B.Fab")
		)
		(fp_line
			(start 0.3048 0.9906)
			(end -0.3048 0.9906)
			(stroke
				(width 0.1)
				(type default)
			)
			(layer "B.Fab")
		)
		(pad "1" smd rect
			(at 0 0 180)
			(size 0.508 0.508)
			(layers "B.Cu" "B.Mask" "B.Paste")
			(net "P3E_CPU0_PE3_OCP_TXN<5>")
		)
		(pad "2" smd rect
			(at 0 0.889 180)
			(size 0.508 0.508)
			(layers "B.Cu" "B.Mask" "B.Paste")
			(net "P3E_OCP_CPU0_PE3_C_TXN<5>")
		)
		(zone
			(layer "B.Cu")
			(hatch none 0.5)
			(connect_pads
				(clearance 0)
			)
			(min_thickness 0.25)
			(keepout
				(tracks allowed)
				(vias not_allowed)
				(pads allowed)
				(copperpour not_allowed)
				(footprints allowed)
			)
			(placement
				(enabled no)
				(sheetname "")
			)
			(fill
				(thermal_gap 0.5)
				(thermal_bridge_width 0.5)
				(island_removal_mode 0)
			)
			(polygon
				(pts
					(xy 448.182238 -52.153058) (xy 447.674238 -52.153058) (xy 447.674238 -51.772058) (xy 448.182238 -51.772058)
				)
			)
		)
		(zone
			(layer "B.Cu")
			(hatch none 0.5)
			(connect_pads
				(clearance 0)
			)
			(min_thickness 0.25)
			(keepout
				(tracks not_allowed)
				(vias allowed)
				(pads allowed)
				(copperpour not_allowed)
				(footprints allowed)
			)
			(placement
				(enabled no)
				(sheetname "")
			)
			(fill
				(thermal_gap 0.5)
				(thermal_bridge_width 0.5)
				(island_removal_mode 0)
			)
			(polygon
				(pts
					(xy 448.182238 -51.772058) (xy 447.674238 -51.772058) (xy 447.674238 -52.153058) (xy 448.182238 -52.153058)
				)
			)
		)
	)
)
